(kicad_pcb
	(version 20260206)
	(generator "pcbnew")
	(generator_version "10.0")
	(general
		(thickness 1.6)
		(legacy_teardrops no)
	)
	(paper "A4")
	(title_block
		(title "12092022_DA0F0TFB6D0_F0T_FAN_BOARD_MP5048_D_brd_v02_OCP.brd")
		(comment 1 "Grand Teton / footprints 370-374 of 924")
	)
	(layers
		(0 "F.Cu" signal "TOP")
		(4 "In1.Cu" signal "GND")
		(6 "In2.Cu" signal "IN1")
		(8 "In3.Cu" signal "IN2")
		(10 "In4.Cu" signal "GND1")
		(2 "B.Cu" signal "BOTTOM")
		(9 "F.Adhes" user "F.Adhesive")
		(11 "B.Adhes" user "B.Adhesive")
		(13 "F.Paste" user "Package Geometry/Pastemask Top")
		(15 "B.Paste" user "Package Geometry/Pastemask Bottom")
		(5 "F.SilkS" user "Ref Des/Silkscreen Top")
		(7 "B.SilkS" user "Ref Des/Silkscreen Bottom")
		(1 "F.Mask" user "Board Geometry/Soldermask Top")
		(3 "B.Mask" user "Board Geometry/Soldermask Bottom")
		(17 "Dwgs.User" user "User.Drawings")
		(19 "Cmts.User" user "User.Comments")
		(21 "Eco1.User" user "User.Eco1")
		(23 "Eco2.User" user "User.Eco2")
		(25 "Edge.Cuts" user "Board Geometry/Outline")
		(27 "Margin" user)
		(31 "F.CrtYd" user "Package Geometry/Place Bound Top")
		(29 "B.CrtYd" user "Package Geometry/Place Bound Bottom")
		(35 "F.Fab" user "Ref Des/Assembly Top")
		(33 "B.Fab" user "Ref Des/Assembly Bottom")
	)
	(footprint ""
		(layer "F.Cu")
		(at 29.464 -133.477 -90)
		(property "Reference" "C1932"
			(at 0 0 270)
			(layer "F.SilkS")
			(hide yes)
			(effects
				(font
					(size 1.27 1.27)
				)
			)
		)
		(property "Value" ""
			(at 0 0 270)
			(layer "F.Fab")
			(effects
				(font
					(size 1.27 1.27)
				)
			)
		)
		(duplicate_pad_numbers_are_jumpers no)
		(fp_line
			(start -0.7874 0.4064)
			(end -0.7874 -0.4064)
			(stroke
				(width 0.1524)
				(type default)
			)
			(layer "F.SilkS")
		)
		(fp_line
			(start 0.7874 0.4064)
			(end -0.7874 0.4064)
			(stroke
				(width 0.1524)
				(type default)
			)
			(layer "F.SilkS")
		)
		(fp_line
			(start -0.7874 -0.4064)
			(end 0.7874 -0.4064)
			(stroke
				(width 0.1524)
				(type default)
			)
			(layer "F.SilkS")
		)
		(fp_line
			(start 0.7874 -0.4064)
			(end 0.7874 0.4064)
			(stroke
				(width 0.1524)
				(type default)
			)
			(layer "F.SilkS")
		)
		(fp_line
			(start -0.67945 0.3048)
			(end -0.67945 -0.305054)
			(stroke
				(width 0.1)
				(type default)
			)
			(layer "F.Fab")
		)
		(fp_line
			(start -0.12065 0.3048)
			(end -0.67945 0.3048)
			(stroke
				(width 0.1)
				(type default)
			)
			(layer "F.Fab")
		)
		(fp_line
			(start 0.120396 0.3048)
			(end 0.120396 0.2794)
			(stroke
				(width 0.1)
				(type default)
			)
			(layer "F.Fab")
		)
		(fp_line
			(start 0.67945 0.3048)
			(end 0.120396 0.3048)
			(stroke
				(width 0.1)
				(type default)
			)
			(layer "F.Fab")
		)
		(fp_line
			(start -0.12065 0.2794)
			(end -0.12065 0.3048)
			(stroke
				(width 0.1)
				(type default)
			)
			(layer "F.Fab")
		)
		(fp_line
			(start 0.120396 0.2794)
			(end -0.12065 0.2794)
			(stroke
				(width 0.1)
				(type default)
			)
			(layer "F.Fab")
		)
		(fp_line
			(start -0.12065 -0.2794)
			(end 0.12065 -0.2794)
			(stroke
				(width 0.1)
				(type default)
			)
			(layer "F.Fab")
		)
		(fp_line
			(start 0.12065 -0.2794)
			(end 0.12065 -0.3048)
			(stroke
				(width 0.1)
				(type default)
			)
			(layer "F.Fab")
		)
		(fp_line
			(start 0.12065 -0.3048)
			(end 0.67945 -0.3048)
			(stroke
				(width 0.1)
				(type default)
			)
			(layer "F.Fab")
		)
		(fp_line
			(start 0.67945 -0.3048)
			(end 0.67945 0.3048)
			(stroke
				(width 0.1)
				(type default)
			)
			(layer "F.Fab")
		)
		(fp_line
			(start -0.67945 -0.305054)
			(end -0.12065 -0.305054)
			(stroke
				(width 0.1)
				(type default)
			)
			(layer "F.Fab")
		)
		(fp_line
			(start -0.12065 -0.305054)
			(end -0.12065 -0.2794)
			(stroke
				(width 0.1)
				(type default)
			)
			(layer "F.Fab")
		)
		(pad "1" smd circle
			(at -0.40005 0 270)
			(size 0 0)
			(layers "F.Cu" "F.Mask" "F.Paste")
			(net "GND")
		)
		(pad "2" smd circle
			(at 0.40005 0 270)
			(size 0 0)
			(layers "F.Cu" "F.Mask" "F.Paste")
			(net "P3V3_AUX")
		)
	)
	(footprint ""
		(layer "F.Cu")
		(at 15.377922 -196.155056 180)
		(property "Reference" "D138"
			(at 5.344922 -0.982726 0)
			(unlocked yes)
			(layer "F.SilkS")
			(effects
				(font
					(size 0.7874 0.5842)
					(thickness 0.1524)
				)
				(justify left)
			)
		)
		(property "Value" ""
			(at 0 0 180)
			(layer "F.Fab")
			(effects
				(font
					(size 1.27 1.27)
				)
			)
		)
		(duplicate_pad_numbers_are_jumpers no)
		(fp_line
			(start 2.032 0.7112)
			(end -1.651 0.7112)
			(stroke
				(width 0.1524)
				(type default)
			)
			(layer "F.SilkS")
		)
		(fp_line
			(start 2.032 -0.7112)
			(end 2.032 0.7112)
			(stroke
				(width 0.1524)
				(type default)
			)
			(layer "F.SilkS")
		)
		(fp_line
			(start 1.905 -0.6858)
			(end 1.905 0.6858)
			(stroke
				(width 0.1524)
				(type default)
			)
			(layer "F.SilkS")
		)
		(fp_line
			(start 1.778 0.6858)
			(end 1.778 -0.6858)
			(stroke
				(width 0.1524)
				(type default)
			)
			(layer "F.SilkS")
		)
		(fp_line
			(start 1.651 -0.6858)
			(end 1.651 0.6858)
			(stroke
				(width 0.1524)
				(type default)
			)
			(layer "F.SilkS")
		)
		(fp_line
			(start 0.299974 -0.500126)
			(end 0.299974 0.500126)
			(stroke
				(width 0.1524)
				(type default)
			)
			(layer "F.SilkS")
		)
		(fp_line
			(start 0.199898 0)
			(end -0.299974 -0.500126)
			(stroke
				(width 0.1524)
				(type default)
			)
			(layer "F.SilkS")
		)
		(fp_line
			(start -0.299974 0.500126)
			(end 0.199898 0)
			(stroke
				(width 0.1524)
				(type default)
			)
			(layer "F.SilkS")
		)
		(fp_line
			(start -0.299974 -0.500126)
			(end -0.299974 0.500126)
			(stroke
				(width 0.1524)
				(type default)
			)
			(layer "F.SilkS")
		)
		(fp_line
			(start -1.651 0.7112)
			(end -1.651 -0.7112)
			(stroke
				(width 0.1524)
				(type default)
			)
			(layer "F.SilkS")
		)
		(fp_line
			(start -1.651 -0.7112)
			(end 2.032 -0.7112)
			(stroke
				(width 0.1524)
				(type default)
			)
			(layer "F.SilkS")
		)
		(fp_line
			(start 1.35001 0.175006)
			(end 0.899922 0.175006)
			(stroke
				(width 0.1)
				(type default)
			)
			(layer "F.Fab")
		)
		(fp_line
			(start 1.35001 -0.225044)
			(end 1.35001 0.175006)
			(stroke
				(width 0.1)
				(type default)
			)
			(layer "F.Fab")
		)
		(fp_line
			(start 0.899922 0.700024)
			(end -0.899922 0.700024)
			(stroke
				(width 0.1)
				(type default)
			)
			(layer "F.Fab")
		)
		(fp_line
			(start 0.899922 0.175006)
			(end 0.899922 0.700024)
			(stroke
				(width 0.1)
				(type default)
			)
			(layer "F.Fab")
		)
		(fp_line
			(start 0.899922 -0.225044)
			(end 1.35001 -0.225044)
			(stroke
				(width 0.1)
				(type default)
			)
			(layer "F.Fab")
		)
		(fp_line
			(start 0.899922 -0.700024)
			(end 0.899922 -0.225044)
			(stroke
				(width 0.1)
				(type default)
			)
			(layer "F.Fab")
		)
		(fp_line
			(start 0.299974 -0.500126)
			(end 0.299974 0.500126)
			(stroke
				(width 0.1)
				(type default)
			)
			(layer "F.Fab")
		)
		(fp_line
			(start 0.199898 0)
			(end -0.299974 -0.500126)
			(stroke
				(width 0.1)
				(type default)
			)
			(layer "F.Fab")
		)
		(fp_line
			(start -0.299974 0.500126)
			(end 0.199898 0)
			(stroke
				(width 0.1)
				(type default)
			)
			(layer "F.Fab")
		)
		(fp_line
			(start -0.299974 -0.500126)
			(end -0.299974 0.500126)
			(stroke
				(width 0.1)
				(type default)
			)
			(layer "F.Fab")
		)
		(fp_line
			(start -0.899922 0.700024)
			(end -0.899922 0.175006)
			(stroke
				(width 0.1)
				(type default)
			)
			(layer "F.Fab")
		)
		(fp_line
			(start -0.899922 0.175006)
			(end -1.35001 0.175006)
			(stroke
				(width 0.1)
				(type default)
			)
			(layer "F.Fab")
		)
		(fp_line
			(start -0.899922 -0.225044)
			(end -0.899922 -0.700024)
			(stroke
				(width 0.1)
				(type default)
			)
			(layer "F.Fab")
		)
		(fp_line
			(start -0.899922 -0.700024)
			(end 0.899922 -0.700024)
			(stroke
				(width 0.1)
				(type default)
			)
			(layer "F.Fab")
		)
		(fp_line
			(start -1.35001 0.175006)
			(end -1.35001 -0.225044)
			(stroke
				(width 0.1)
				(type default)
			)
			(layer "F.Fab")
		)
		(fp_line
			(start -1.35001 -0.225044)
			(end -0.899922 -0.225044)
			(stroke
				(width 0.1)
				(type default)
			)
			(layer "F.Fab")
		)
		(fp_text user "-"
			(at 0.518922 -1.305306 180)
			(unlocked yes)
			(layer "F.SilkS")
			(effects
				(font
					(size 1.905 1.4224)
					(thickness 0.1524)
				)
				(justify left)
			)
		)
		(fp_text user "+"
			(at -2.656078 -1.178306 180)
			(unlocked yes)
			(layer "F.SilkS")
			(effects
				(font
					(size 1.905 1.4224)
					(thickness 0.1524)
				)
				(justify left)
			)
		)
		(fp_text user "-"
			(at 1.8288 -0.24765 180)
			(unlocked yes)
			(layer "F.Fab")
			(effects
				(font
					(size 1.905 1.4224)
					(thickness 0.1524)
				)
				(justify left)
			)
		)
		(fp_text user "+"
			(at -2.794 -0.19685 180)
			(unlocked yes)
			(layer "F.Fab")
			(effects
				(font
					(size 1.905 1.4224)
					(thickness 0.1524)
				)
				(justify left)
			)
		)
		(pad "1" smd rect
			(at -1.0922 0)
			(size 0.8128 0.8636)
			(layers "F.Cu" "F.Mask" "F.Paste")
			(net "FAN_6_TACH_IL_R")
		)
		(pad "2" smd rect
			(at 1.0922 0 180)
			(size 0.8128 0.8636)
			(layers "F.Cu" "F.Mask" "F.Paste")
			(net "FAN_6_TACH_IL_D")
		)
	)
	(footprint ""
		(layer "F.Cu")
		(at 43.561 -176.911)
		(property "Reference" "R5101"
			(at 0 0 0)
			(layer "F.SilkS")
			(hide yes)
			(effects
				(font
					(size 1.27 1.27)
				)
			)
		)
		(property "Value" ""
			(at 0 0 0)
			(layer "F.Fab")
			(effects
				(font
					(size 1.27 1.27)
				)
			)
		)
		(duplicate_pad_numbers_are_jumpers no)
		(fp_line
			(start -0.7874 -0.4064)
			(end 0.7874 -0.4064)
			(stroke
				(width 0.1524)
				(type default)
			)
			(layer "F.SilkS")
		)
		(fp_line
			(start -0.7874 0.4064)
			(end -0.7874 -0.4064)
			(stroke
				(width 0.1524)
				(type default)
			)
			(layer "F.SilkS")
		)
		(fp_line
			(start 0.7874 -0.4064)
			(end 0.7874 0.4064)
			(stroke
				(width 0.1524)
				(type default)
			)
			(layer "F.SilkS")
		)
		(fp_line
			(start 0.7874 0.4064)
			(end -0.7874 0.4064)
			(stroke
				(width 0.1524)
				(type default)
			)
			(layer "F.SilkS")
		)
		(fp_line
			(start -0.67945 -0.305054)
			(end -0.12065 -0.305054)
			(stroke
				(width 0.1)
				(type default)
			)
			(layer "F.Fab")
		)
		(fp_line
			(start -0.67945 0.3048)
			(end -0.67945 -0.305054)
			(stroke
				(width 0.1)
				(type default)
			)
			(layer "F.Fab")
		)
		(fp_line
			(start -0.12065 -0.305054)
			(end -0.12065 -0.2794)
			(stroke
				(width 0.1)
				(type default)
			)
			(layer "F.Fab")
		)
		(fp_line
			(start -0.12065 -0.2794)
			(end 0.12065 -0.2794)
			(stroke
				(width 0.1)
				(type default)
			)
			(layer "F.Fab")
		)
		(fp_line
			(start -0.12065 0.2794)
			(end -0.12065 0.3048)
			(stroke
				(width 0.1)
				(type default)
			)
			(layer "F.Fab")
		)
		(fp_line
			(start -0.12065 0.3048)
			(end -0.67945 0.3048)
			(stroke
				(width 0.1)
				(type default)
			)
			(layer "F.Fab")
		)
		(fp_line
			(start 0.120396 0.2794)
			(end -0.12065 0.2794)
			(stroke
				(width 0.1)
				(type default)
			)
			(layer "F.Fab")
		)
		(fp_line
			(start 0.120396 0.3048)
			(end 0.120396 0.2794)
			(stroke
				(width 0.1)
				(type default)
			)
			(layer "F.Fab")
		)
		(fp_line
			(start 0.12065 -0.3048)
			(end 0.67945 -0.3048)
			(stroke
				(width 0.1)
				(type default)
			)
			(layer "F.Fab")
		)
		(fp_line
			(start 0.12065 -0.2794)
			(end 0.12065 -0.3048)
			(stroke
				(width 0.1)
				(type default)
			)
			(layer "F.Fab")
		)
		(fp_line
			(start 0.67945 -0.3048)
			(end 0.67945 0.3048)
			(stroke
				(width 0.1)
				(type default)
			)
			(layer "F.Fab")
		)
		(fp_line
			(start 0.67945 0.3048)
			(end 0.120396 0.3048)
			(stroke
				(width 0.1)
				(type default)
			)
			(layer "F.Fab")
		)
		(pad "1" smd circle
			(at -0.40005 0)
			(size 0 0)
			(layers "F.Cu" "F.Mask" "F.Paste")
			(net "FAN_3_FAIL_LED")
		)
		(pad "2" smd circle
			(at 0.40005 0)
			(size 0 0)
			(layers "F.Cu" "F.Mask" "F.Paste")
			(net "FAN_3_FAIL_R_LED")
		)
	)
	(footprint ""
		(layer "F.Cu")
		(at 25.527 -133.858)
		(property "Reference" "R5680"
			(at 0 0 0)
			(layer "F.SilkS")
			(hide yes)
			(effects
				(font
					(size 1.27 1.27)
				)
			)
		)
		(property "Value" ""
			(at 0 0 0)
			(layer "F.Fab")
			(effects
				(font
					(size 1.27 1.27)
				)
			)
		)
		(duplicate_pad_numbers_are_jumpers no)
		(fp_line
			(start -0.7874 -0.4064)
			(end 0.7874 -0.4064)
			(stroke
				(width 0.1524)
				(type default)
			)
			(layer "F.SilkS")
		)
		(fp_line
			(start -0.7874 0.4064)
			(end -0.7874 -0.4064)
			(stroke
				(width 0.1524)
				(type default)
			)
			(layer "F.SilkS")
		)
		(fp_line
			(start 0.7874 -0.4064)
			(end 0.7874 0.4064)
			(stroke
				(width 0.1524)
				(type default)
			)
			(layer "F.SilkS")
		)
		(fp_line
			(start 0.7874 0.4064)
			(end -0.7874 0.4064)
			(stroke
				(width 0.1524)
				(type default)
			)
			(layer "F.SilkS")
		)
		(fp_line
			(start -0.67945 -0.305054)
			(end -0.12065 -0.305054)
			(stroke
				(width 0.1)
				(type default)
			)
			(layer "F.Fab")
		)
		(fp_line
			(start -0.67945 0.3048)
			(end -0.67945 -0.305054)
			(stroke
				(width 0.1)
				(type default)
			)
			(layer "F.Fab")
		)
		(fp_line
			(start -0.12065 -0.305054)
			(end -0.12065 -0.2794)
			(stroke
				(width 0.1)
				(type default)
			)
			(layer "F.Fab")
		)
		(fp_line
			(start -0.12065 -0.2794)
			(end 0.12065 -0.2794)
			(stroke
				(width 0.1)
				(type default)
			)
			(layer "F.Fab")
		)
		(fp_line
			(start -0.12065 0.2794)
			(end -0.12065 0.3048)
			(stroke
				(width 0.1)
				(type default)
			)
			(layer "F.Fab")
		)
		(fp_line
			(start -0.12065 0.3048)
			(end -0.67945 0.3048)
			(stroke
				(width 0.1)
				(type default)
			)
			(layer "F.Fab")
		)
		(fp_line
			(start 0.120396 0.2794)
			(end -0.12065 0.2794)
			(stroke
				(width 0.1)
				(type default)
			)
			(layer "F.Fab")
		)
		(fp_line
			(start 0.120396 0.3048)
			(end 0.120396 0.2794)
			(stroke
				(width 0.1)
				(type default)
			)
			(layer "F.Fab")
		)
		(fp_line
			(start 0.12065 -0.3048)
			(end 0.67945 -0.3048)
			(stroke
				(width 0.1)
				(type default)
			)
			(layer "F.Fab")
		)
		(fp_line
			(start 0.12065 -0.2794)
			(end 0.12065 -0.3048)
			(stroke
				(width 0.1)
				(type default)
			)
			(layer "F.Fab")
		)
		(fp_line
			(start 0.67945 -0.3048)
			(end 0.67945 0.3048)
			(stroke
				(width 0.1)
				(type default)
			)
			(layer "F.Fab")
		)
		(fp_line
			(start 0.67945 0.3048)
			(end 0.120396 0.3048)
			(stroke
				(width 0.1)
				(type default)
			)
			(layer "F.Fab")
		)
		(pad "1" smd rect
			(at -0.40005 0 180)
			(size 0.4572 0.508)
			(layers "F.Cu" "F.Mask" "F.Paste")
			(net "U330_FAN FS_N")
		)
		(pad "2" smd rect
			(at 0.40005 0 180)
			(size 0.4572 0.508)
			(layers "F.Cu" "F.Mask" "F.Paste")
			(net "U330_FAN FAIL_N")
		)
	)
	(footprint ""
		(layer "F.Cu")
		(at 17.399 -211.836 180)
		(property "Reference" "R5319"
			(at 0 0 180)
			(layer "F.SilkS")
			(hide yes)
			(effects
				(font
					(size 1.27 1.27)
				)
			)
		)
		(property "Value" ""
			(at 0 0 180)
			(layer "F.Fab")
			(effects
				(font
					(size 1.27 1.27)
				)
			)
		)
		(duplicate_pad_numbers_are_jumpers no)
		(fp_line
			(start 0.7874 0.4064)
			(end -0.7874 0.4064)
			(stroke
				(width 0.1524)
				(type default)
			)
			(layer "F.SilkS")
		)
		(fp_line
			(start 0.7874 -0.4064)
			(end 0.7874 0.4064)
			(stroke
				(width 0.1524)
				(type default)
			)
			(layer "F.SilkS")
		)
		(fp_line
			(start -0.7874 0.4064)
			(end -0.7874 -0.4064)
			(stroke
				(width 0.1524)
				(type default)
			)
			(layer "F.SilkS")
		)
		(fp_line
			(start -0.7874 -0.4064)
			(end 0.7874 -0.4064)
			(stroke
				(width 0.1524)
				(type default)
			)
			(layer "F.SilkS")
		)
		(fp_line
			(start 0.67945 0.3048)
			(end 0.120396 0.3048)
			(stroke
				(width 0.1)
				(type default)
			)
			(layer "F.Fab")
		)
		(fp_line
			(start 0.67945 -0.3048)
			(end 0.67945 0.3048)
			(stroke
				(width 0.1)
				(type default)
			)
			(layer "F.Fab")
		)
		(fp_line
			(start 0.12065 -0.2794)
			(end 0.12065 -0.3048)
			(stroke
				(width 0.1)
				(type default)
			)
			(layer "F.Fab")
		)
		(fp_line
			(start 0.12065 -0.3048)
			(end 0.67945 -0.3048)
			(stroke
				(width 0.1)
				(type default)
			)
			(layer "F.Fab")
		)
		(fp_line
			(start 0.120396 0.3048)
			(end 0.120396 0.2794)
			(stroke
				(width 0.1)
				(type default)
			)
			(layer "F.Fab")
		)
		(fp_line
			(start 0.120396 0.2794)
			(end -0.12065 0.2794)
			(stroke
				(width 0.1)
				(type default)
			)
			(layer "F.Fab")
		)
		(fp_line
			(start -0.12065 0.3048)
			(end -0.67945 0.3048)
			(stroke
				(width 0.1)
				(type default)
			)
			(layer "F.Fab")
		)
		(fp_line
			(start -0.12065 0.2794)
			(end -0.12065 0.3048)
			(stroke
				(width 0.1)
				(type default)
			)
			(layer "F.Fab")
		)
		(fp_line
			(start -0.12065 -0.2794)
			(end 0.12065 -0.2794)
			(stroke
				(width 0.1)
				(type default)
			)
			(layer "F.Fab")
		)
		(fp_line
			(start -0.12065 -0.305054)
			(end -0.12065 -0.2794)
			(stroke
				(width 0.1)
				(type default)
			)
			(layer "F.Fab")
		)
		(fp_line
			(start -0.67945 0.3048)
			(end -0.67945 -0.305054)
			(stroke
				(width 0.1)
				(type default)
			)
			(layer "F.Fab")
		)
		(fp_line
			(start -0.67945 -0.305054)
			(end -0.12065 -0.305054)
			(stroke
				(width 0.1)
				(type default)
			)
			(layer "F.Fab")
		)
		(pad "1" smd rect
			(at -0.40005 0)
			(size 0.4572 0.508)
			(layers "F.Cu" "F.Mask" "F.Paste")
			(net "FAN_6_TACH_OL_R")
		)
		(pad "2" smd rect
			(at 0.40005 0)
			(size 0.4572 0.508)
			(layers "F.Cu" "F.Mask" "F.Paste")
			(net "FAN_6_TACH_OL")
		)
	)
)
